FILE_TYPE=LIBRARY_PARTS;
primitive 'MOSFET_NCH_1D3S';
  pin
    '3':
      PIN_NUMBER='(3)';
      BIDIRECTIONAL='TRUE';
      INPUT_LOAD='(-0.01,0.01)';
      OUTPUT_LOAD='(1.0,-1.0)';
    '5':
      PIN_NUMBER='(5)';
      BIDIRECTIONAL='TRUE';
      INPUT_LOAD='(-0.01,0.01)';
      OUTPUT_LOAD='(1.0,-1.0)';
    '2':
      PIN_NUMBER='(2)';
      BIDIRECTIONAL='TRUE';
      INPUT_LOAD='(-0.01,0.01)';
      OUTPUT_LOAD='(1.0,-1.0)';
    '4':
      PIN_NUMBER='(4)';
      INPUT_LOAD='(-0.01,0.01)';
    '1':
      PIN_NUMBER='(1)';
      BIDIRECTIONAL='TRUE';
      INPUT_LOAD='(-0.01,0.01)';
      OUTPUT_LOAD='(1.0,-1.0)';
  end_pin;
  body
    PART_NAME='MOSFET_NCH_1D3S';
    BODY_NAME='MOSFET_NCH_1D3S';
    JEDEC_TYPE='SOIC8-PW';
    PHYS_DES_PREFIX='PQ';
    CLASS='DISCRETE';
  end_body;
end_primitive;

END.
